# T6G (Grand Teton) — schematic netlist excerpt (pin names and nets, part order shuffled) for the footprints in the layout excerpt that follows; sources: Cadence DE-HDL packaged netlist, KiCad conversion of 04192023_DAF0TMB3IC0_F0TG_MB_C_brd_V02_OCP.brd

J65  PICOPROBE_BXA  DELTA-L 4.0 EMPTY  pkg TRIANG_LAUNCH_3PXB  page 229
  \1_p\  = DELTA_L_85_5INCH_IN1_DP
  \2_n\  = DELTA_L_85_5INCH_IN1_DN
  \3_g\  = DELTA_L_GND_1

(kicad_pcb
	(version 20260206)
	(generator "pcbnew")
	(generator_version "10.0")
	(general
		(thickness 1.6)
		(legacy_teardrops no)
	)
	(paper "A4")
	(title_block
		(title "04192023_DAF0TMB3IC0_F0TG_MB_C_brd_V02_OCP.brd")
		(comment 1 "Grand Teton / footprints 3359-3359 of 8354")
	)
	(layers
		(0 "F.Cu" signal "TOP")
		(4 "In1.Cu" signal "GND")
		(6 "In2.Cu" signal "IN1")
		(8 "In3.Cu" signal "GND1")
		(10 "In4.Cu" signal "IN2")
		(12 "In5.Cu" signal "GND2")
		(14 "In6.Cu" signal "IN3")
		(16 "In7.Cu" signal "GND3")
		(18 "In8.Cu" signal "VCC")
		(20 "In9.Cu" signal "VCC1")
		(22 "In10.Cu" signal "GND4")
		(24 "In11.Cu" signal "IN4")
		(26 "In12.Cu" signal "GND5")
		(28 "In13.Cu" signal "IN5")
		(30 "In14.Cu" signal "GND6")
		(32 "In15.Cu" signal "IN6")
		(34 "In16.Cu" signal "GND7")
		(2 "B.Cu" signal "BOTTOM")
		(9 "F.Adhes" user "F.Adhesive")
		(11 "B.Adhes" user "B.Adhesive")
		(13 "F.Paste" user "Package Geometry/Pastemask Top")
		(15 "B.Paste" user "Package Geometry/Pastemask Bottom")
		(5 "F.SilkS" user "Ref Des/Silkscreen Top")
		(7 "B.SilkS" user "Ref Des/Silkscreen Bottom")
		(1 "F.Mask" user "Board Geometry/Soldermask Top")
		(3 "B.Mask" user "Board Geometry/Soldermask Bottom")
		(17 "Dwgs.User" user "User.Drawings")
		(19 "Cmts.User" user "User.Comments")
		(21 "Eco1.User" user "User.Eco1")
		(23 "Eco2.User" user "User.Eco2")
		(25 "Edge.Cuts" user "Board Geometry/Outline")
		(27 "Margin" user)
		(31 "F.CrtYd" user "Package Geometry/Place Bound Top")
		(29 "B.CrtYd" user "Package Geometry/Place Bound Bottom")
		(35 "F.Fab" user "Ref Des/Assembly Top")
		(33 "B.Fab" user "Ref Des/Assembly Bottom")
	)
	(footprint ""
		(layer "F.Cu")
		(at 366.288574 5.082794 180)
		(property "Reference" "J65"
			(at -4.652264 -1.360932 90)
			(unlocked yes)
			(layer "F.SilkS")
			(effects
				(font
					(size 0.7874 0.5842)
					(thickness 0.1524)
				)
				(justify left)
			)
		)
		(property "Value" ""
			(at 0 0 180)
			(layer "F.Fab")
			(effects
				(font
					(size 1.27 1.27)
				)
			)
		)
		(duplicate_pad_numbers_are_jumpers no)
		(fp_line
			(start 1.2192 2.06756)
			(end -1.2192 2.06756)
			(stroke
				(width 0.1524)
				(type default)
			)
			(layer "F.SilkS")
		)
		(fp_line
			(start 1.2192 -2.06756)
			(end 1.2192 2.06756)
			(stroke
				(width 0.1524)
				(type default)
			)
			(layer "F.SilkS")
		)
		(fp_line
			(start -1.2192 2.06756)
			(end -1.2192 -2.06756)
			(stroke
				(width 0.1524)
				(type default)
			)
			(layer "F.SilkS")
		)
		(fp_line
			(start -1.2192 -2.06756)
			(end 1.2192 -2.06756)
			(stroke
				(width 0.1524)
				(type default)
			)
			(layer "F.SilkS")
		)
		(pad "" np_thru_hole circle
			(at -2.8829 -1.27 90)
			(size 1.0414 1.0414)
			(drill 1.0414)
			(layers "*.Cu" "*.Mask")
			(clearance 0.381)
			(thermal_gap 0.381)
		)
		(pad "" np_thru_hole circle
			(at -2.8829 1.27 90)
			(size 1.0414 1.0414)
			(drill 1.0414)
			(layers "*.Cu" "*.Mask")
			(clearance 0.381)
			(thermal_gap 0.381)
		)
		(pad "" np_thru_hole circle
			(at 3.4671 -1.27 90)
			(size 1.0414 1.0414)
			(drill 1.0414)
			(layers "*.Cu" "*.Mask")
			(clearance 0.381)
			(thermal_gap 0.381)
		)
		(pad "" np_thru_hole circle
			(at 3.4671 1.27 90)
			(size 1.0414 1.0414)
			(drill 1.0414)
			(layers "*.Cu" "*.Mask")
			(clearance 0.381)
			(thermal_gap 0.381)
		)
		(pad "1" smd rect
			(at 0.8255 -0.249936 90)
			(size 0.3048 0.508)
			(layers "F.Cu" "F.Mask" "F.Paste")
			(net "DELTA_L_85_5INCH_IN1_DP")
		)
		(pad "2" smd rect
			(at 0.8255 0.249936 90)
			(size 0.3048 0.508)
			(layers "F.Cu" "F.Mask" "F.Paste")
			(net "DELTA_L_85_5INCH_IN1_DN")
		)
		(pad "3" smd circle
			(at 0 0 180)
			(size 0 0)
			(layers "F.Cu" "F.Mask" "F.Paste")
			(net "DELTA_L_GND_1")
		)
		(zone
			(layer "F.Cu")
			(hatch none 0.5)
			(connect_pads
				(clearance 0)
			)
			(min_thickness 0.25)
			(keepout
				(tracks not_allowed)
				(vias allowed)
				(pads allowed)
				(copperpour not_allowed)
				(footprints allowed)
			)
			(placement
				(enabled no)
				(sheetname "")
			)
			(fill
				(thermal_gap 0.5)
				(thermal_bridge_width 0.5)
				(island_removal_mode 0)
			)
			(polygon
				(pts
					(xy 365.170974 5.631434) (xy 365.170974 5.53593) (xy 365.767874 5.53593) (xy 365.767874 5.12953)
					(xy 365.170974 5.12953) (xy 365.170974 5.036058) (xy 365.767874 5.036058) (xy 365.767874 4.629658)
					(xy 365.170974 4.629658) (xy 365.170974 4.534154) (xy 365.869474 4.534154) (xy 365.869474 5.631434)
				)
			)
		)
		(zone
			(layers "F.Cu" "B.Cu" "In1.Cu" "In2.Cu" "In3.Cu" "In4.Cu" "In5.Cu" "In6.Cu"
				"In7.Cu" "In8.Cu" "In9.Cu" "In10.Cu" "In11.Cu" "In12.Cu" "In13.Cu" "In14.Cu"
				"In15.Cu" "In16.Cu"
			)
			(hatch none 0.5)
			(connect_pads
				(clearance 0)
			)
			(min_thickness 0.25)
			(keepout
				(tracks not_allowed)
				(vias allowed)
				(pads allowed)
				(copperpour not_allowed)
				(footprints allowed)
			)
			(placement
				(enabled no)
				(sheetname "")
			)
			(fill
				(thermal_gap 0.5)
				(thermal_bridge_width 0.5)
				(island_removal_mode 0)
			)
			(polygon
				(pts
					(arc
						(start 363.748574 3.812794)
						(mid 361.894374 3.812794)
						(end 363.748574 3.812794)
					)
				)
			)
		)
		(zone
			(layers "F.Cu" "B.Cu" "In1.Cu" "In2.Cu" "In3.Cu" "In4.Cu" "In5.Cu" "In6.Cu"
				"In7.Cu" "In8.Cu" "In9.Cu" "In10.Cu" "In11.Cu" "In12.Cu" "In13.Cu" "In14.Cu"
				"In15.Cu" "In16.Cu"
			)
			(hatch none 0.5)
			(connect_pads
				(clearance 0)
			)
			(min_thickness 0.25)
			(keepout
				(tracks not_allowed)
				(vias allowed)
				(pads allowed)
				(copperpour not_allowed)
				(footprints allowed)
			)
			(placement
				(enabled no)
				(sheetname "")
			)
			(fill
				(thermal_gap 0.5)
				(thermal_bridge_width 0.5)
				(island_removal_mode 0)
			)
			(polygon
				(pts
					(arc
						(start 363.748574 6.352794)
						(mid 361.894374 6.352794)
						(end 363.748574 6.352794)
					)
				)
			)
		)
		(zone
			(layers "F.Cu" "B.Cu" "In1.Cu" "In2.Cu" "In3.Cu" "In4.Cu" "In5.Cu" "In6.Cu"
				"In7.Cu" "In8.Cu" "In9.Cu" "In10.Cu" "In11.Cu" "In12.Cu" "In13.Cu" "In14.Cu"
				"In15.Cu" "In16.Cu"
			)
			(hatch none 0.5)
			(connect_pads
				(clearance 0)
			)
			(min_thickness 0.25)
			(keepout
				(tracks not_allowed)
				(vias allowed)
				(pads allowed)
				(copperpour not_allowed)
				(footprints allowed)
			)
			(placement
				(enabled no)
				(sheetname "")
			)
			(fill
				(thermal_gap 0.5)
				(thermal_bridge_width 0.5)
				(island_removal_mode 0)
			)
			(polygon
				(pts
					(arc
						(start 370.098574 3.812794)
						(mid 368.244374 3.812794)
						(end 370.098574 3.812794)
					)
				)
			)
		)
		(zone
			(layers "F.Cu" "B.Cu" "In1.Cu" "In2.Cu" "In3.Cu" "In4.Cu" "In5.Cu" "In6.Cu"
				"In7.Cu" "In8.Cu" "In9.Cu" "In10.Cu" "In11.Cu" "In12.Cu" "In13.Cu" "In14.Cu"
				"In15.Cu" "In16.Cu"
			)
			(hatch none 0.5)
			(connect_pads
				(clearance 0)
			)
			(min_thickness 0.25)
			(keepout
				(tracks not_allowed)
				(vias allowed)
				(pads allowed)
				(copperpour not_allowed)
				(footprints allowed)
			)
			(placement
				(enabled no)
				(sheetname "")
			)
			(fill
				(thermal_gap 0.5)
				(thermal_bridge_width 0.5)
				(island_removal_mode 0)
			)
			(polygon
				(pts
					(arc
						(start 370.098574 6.352794)
						(mid 368.244374 6.352794)
						(end 370.098574 6.352794)
					)
				)
			)
		)
	)
)
